(kicad_pcb
	(version 20260206)
	(generator "pcbnew")
	(generator_version "10.0")
	(general
		(thickness 1.6)
		(legacy_teardrops no)
	)
	(paper "A4")
	(title_block
		(title "peb — Lightning_PEB_BRD.brd")
		(comment 1 "Lightning (Wiwynn / Facebook NVMe JBOF) / footprints 685-692 of 2563")
	)
	(layers
		(0 "F.Cu" signal "TOP")
		(4 "In1.Cu" signal "L2GND")
		(6 "In2.Cu" signal "L3")
		(8 "In3.Cu" signal "L4VCC")
		(10 "In4.Cu" signal "L5VCC")
		(12 "In5.Cu" signal "L6")
		(14 "In6.Cu" signal "L7GND")
		(2 "B.Cu" signal "BOTTOM")
		(9 "F.Adhes" user "F.Adhesive")
		(11 "B.Adhes" user "B.Adhesive")
		(13 "F.Paste" user "Package Geometry/Pastemask Top")
		(15 "B.Paste" user "Package Geometry/Pastemask Bottom")
		(5 "F.SilkS" user "Ref Des/Silkscreen Top")
		(7 "B.SilkS" user "Ref Des/Silkscreen Bottom")
		(1 "F.Mask" user "Board Geometry/Soldermask Top")
		(3 "B.Mask" user "Board Geometry/Soldermask Bottom")
		(17 "Dwgs.User" user "User.Drawings")
		(19 "Cmts.User" user "User.Comments")
		(21 "Eco1.User" user "User.Eco1")
		(23 "Eco2.User" user "User.Eco2")
		(25 "Edge.Cuts" user "Board Geometry/Outline")
		(27 "Margin" user)
		(31 "F.CrtYd" user "Package Geometry/Place Bound Top")
		(29 "B.CrtYd" user "Package Geometry/Place Bound Bottom")
		(35 "F.Fab" user "Ref Des/Assembly Top")
		(33 "B.Fab" user "Ref Des/Assembly Bottom")
	)
	(footprint ""
		(layer "F.Cu")
		(at 88.9 -42.2148)
		(property "Reference" "PG5"
			(at 0 0 0)
			(layer "F.SilkS")
			(hide yes)
			(effects
				(font
					(size 1.27 1.27)
				)
			)
		)
		(property "Value" "GAP-CLOSE-PWR-3-GP"
			(at 0.0254 -6.5786 0)
			(unlocked yes)
			(layer "F.Fab")
			(hide yes)
			(effects
				(font
					(size 1.016 1.016)
					(thickness 0.1524)
				)
			)
		)
		(property "Device Type" "GAP-CLOSE-PWR-3"
			(at 0.0254 -8.255 0)
			(unlocked yes)
			(layer "F.Fab")
			(hide yes)
			(effects
				(font
					(size 1.016 1.016)
					(thickness 0.1524)
				)
			)
		)
		(duplicate_pad_numbers_are_jumpers no)
		(fp_rect
			(start -0.7112 0.4572)
			(end 0.7112 -0.4572)
			(stroke
				(width 0)
				(type default)
			)
			(fill no)
			(layer "F.CrtYd")
		)
		(fp_poly
			(pts
				(xy -0.7112 -0.4572) (xy 0.7112 -0.4572) (xy 0.7112 0.4572) (xy -0.7112 0.4572)
			)
			(stroke
				(width 0)
				(type default)
			)
			(fill no)
			(layer "F.Fab")
		)
		(pad "1" smd rect
			(at -0.3048 0)
			(size 0.6604 0.762)
			(layers "F.Cu" "F.Mask" "F.Paste")
			(net "P3V3_PWR")
		)
		(pad "2" smd rect
			(at 0.3048 0)
			(size 0.6604 0.762)
			(layers "F.Cu" "F.Mask" "F.Paste")
			(net "P3V3_STBY")
		)
	)
	(footprint ""
		(layer "F.Cu")
		(at 24.715978 -71.521828 90)
		(property "Reference" "R379"
			(at 0 0 90)
			(layer "F.SilkS")
			(hide yes)
			(effects
				(font
					(size 1.27 1.27)
				)
			)
		)
		(property "Value" "33R2J-2-GP"
			(at 0.064008 -3.993896 90)
			(unlocked yes)
			(layer "F.Fab")
			(hide yes)
			(effects
				(font
					(size 1.016 1.016)
					(thickness 0.1524)
				)
			)
		)
		(property "Device Type" "R402H16"
			(at 0.064008 -5.517896 90)
			(unlocked yes)
			(layer "F.Fab")
			(hide yes)
			(effects
				(font
					(size 1.016 1.016)
					(thickness 0.1524)
				)
			)
		)
		(duplicate_pad_numbers_are_jumpers no)
		(fp_line
			(start 0.508 -0.9398)
			(end -0.508 -0.9398)
			(stroke
				(width 0.1524)
				(type default)
			)
			(layer "F.SilkS")
		)
		(fp_line
			(start -0.508 -0.9398)
			(end -0.508 0.9398)
			(stroke
				(width 0.1524)
				(type default)
			)
			(layer "F.SilkS")
		)
		(fp_rect
			(start -0.508 0.9398)
			(end 0.508 -0.9398)
			(stroke
				(width 0)
				(type default)
			)
			(fill no)
			(layer "F.CrtYd")
		)
		(fp_rect
			(start -0.508 0.9398)
			(end 0.508 -0.9398)
			(stroke
				(width 0)
				(type default)
			)
			(fill no)
			(layer "F.Fab")
		)
		(pad "1" smd custom
			(at 0 -0.4445 90)
			(size 0.1397 0.1397)
			(layers "F.Cu" "F.Mask" "F.Paste")
			(net "CLK_50M_RMII_PHY_IN")
			(options
				(clearance outline)
				(anchor circle)
			)
			(primitives
				(gr_poly
					(pts
						(arc
							(start -0.1778 -0.2794)
							(mid -0.249642 -0.249642)
							(end -0.2794 -0.1778)
						)
						(arc
							(start -0.2794 0.1778)
							(mid -0.249642 0.249642)
							(end -0.1778 0.2794)
						)
						(arc
							(start 0.1778 0.2794)
							(mid 0.249642 0.249642)
							(end 0.2794 0.1778)
						)
						(arc
							(start 0.2794 -0.1778)
							(mid 0.249642 -0.249642)
							(end 0.1778 -0.2794)
						)
					)
					(width 0)
					(fill yes)
				)
			)
		)
		(pad "2" smd custom
			(at 0 0.4445 90)
			(size 0.1397 0.1397)
			(layers "F.Cu" "F.Mask" "F.Paste")
			(net "CLK_50M_RMII_PHY")
			(options
				(clearance outline)
				(anchor circle)
			)
			(primitives
				(gr_poly
					(pts
						(arc
							(start -0.1778 -0.2794)
							(mid -0.249642 -0.249642)
							(end -0.2794 -0.1778)
						)
						(arc
							(start -0.2794 0.1778)
							(mid -0.249642 0.249642)
							(end -0.1778 0.2794)
						)
						(arc
							(start 0.1778 0.2794)
							(mid 0.249642 0.249642)
							(end 0.2794 0.1778)
						)
						(arc
							(start 0.2794 -0.1778)
							(mid 0.249642 -0.249642)
							(end 0.1778 -0.2794)
						)
					)
					(width 0)
					(fill yes)
				)
			)
		)
	)
	(footprint ""
		(layer "F.Cu")
		(at 192.9384 -24.0538 90)
		(property "Reference" "R834"
			(at 0 0 90)
			(layer "F.SilkS")
			(hide yes)
			(effects
				(font
					(size 1.27 1.27)
				)
			)
		)
		(property "Value" "4K7R2F-GP"
			(at 0.064008 -3.993896 90)
			(unlocked yes)
			(layer "F.Fab")
			(hide yes)
			(effects
				(font
					(size 1.016 1.016)
					(thickness 0.1524)
				)
			)
		)
		(property "Device Type" "R402H16"
			(at 0.064008 -5.517896 90)
			(unlocked yes)
			(layer "F.Fab")
			(hide yes)
			(effects
				(font
					(size 1.016 1.016)
					(thickness 0.1524)
				)
			)
		)
		(duplicate_pad_numbers_are_jumpers no)
		(fp_line
			(start 0.508 -0.9398)
			(end -0.508 -0.9398)
			(stroke
				(width 0.1524)
				(type default)
			)
			(layer "F.SilkS")
		)
		(fp_line
			(start -0.508 -0.9398)
			(end -0.508 0.9398)
			(stroke
				(width 0.1524)
				(type default)
			)
			(layer "F.SilkS")
		)
		(fp_rect
			(start -0.508 0.9398)
			(end 0.508 -0.9398)
			(stroke
				(width 0)
				(type default)
			)
			(fill no)
			(layer "F.CrtYd")
		)
		(fp_rect
			(start -0.508 0.9398)
			(end 0.508 -0.9398)
			(stroke
				(width 0)
				(type default)
			)
			(fill no)
			(layer "F.Fab")
		)
		(pad "1" smd custom
			(at 0 -0.4445 90)
			(size 0.1397 0.1397)
			(layers "F.Cu" "F.Mask" "F.Paste")
			(net "GND")
			(options
				(clearance outline)
				(anchor circle)
			)
			(primitives
				(gr_poly
					(pts
						(arc
							(start -0.1778 -0.2794)
							(mid -0.249642 -0.249642)
							(end -0.2794 -0.1778)
						)
						(arc
							(start -0.2794 0.1778)
							(mid -0.249642 0.249642)
							(end -0.1778 0.2794)
						)
						(arc
							(start 0.1778 0.2794)
							(mid 0.249642 0.249642)
							(end 0.2794 0.1778)
						)
						(arc
							(start 0.2794 -0.1778)
							(mid 0.249642 -0.249642)
							(end 0.1778 -0.2794)
						)
					)
					(width 0)
					(fill yes)
				)
			)
		)
		(pad "2" smd custom
			(at 0 0.4445 90)
			(size 0.1397 0.1397)
			(layers "F.Cu" "F.Mask" "F.Paste")
			(net "U56_A2")
			(options
				(clearance outline)
				(anchor circle)
			)
			(primitives
				(gr_poly
					(pts
						(arc
							(start -0.1778 -0.2794)
							(mid -0.249642 -0.249642)
							(end -0.2794 -0.1778)
						)
						(arc
							(start -0.2794 0.1778)
							(mid -0.249642 0.249642)
							(end -0.1778 0.2794)
						)
						(arc
							(start 0.1778 0.2794)
							(mid 0.249642 0.249642)
							(end 0.2794 0.1778)
						)
						(arc
							(start 0.2794 -0.1778)
							(mid 0.249642 -0.249642)
							(end 0.1778 -0.2794)
						)
					)
					(width 0)
					(fill yes)
				)
			)
		)
	)
	(footprint ""
		(layer "F.Cu")
		(at 208.284572 -12.542266 180)
		(property "Reference" "R7892"
			(at 0 0 180)
			(layer "F.SilkS")
			(hide yes)
			(effects
				(font
					(size 1.27 1.27)
				)
			)
		)
		(property "Value" "0R2J-2-GP"
			(at 0.064008 -3.993896 180)
			(unlocked yes)
			(layer "F.Fab")
			(hide yes)
			(effects
				(font
					(size 1.016 1.016)
					(thickness 0.1524)
				)
			)
		)
		(property "Device Type" "R402H16"
			(at 0.064008 -5.517896 180)
			(unlocked yes)
			(layer "F.Fab")
			(hide yes)
			(effects
				(font
					(size 1.016 1.016)
					(thickness 0.1524)
				)
			)
		)
		(duplicate_pad_numbers_are_jumpers no)
		(fp_line
			(start 0.508 -0.9398)
			(end -0.508 -0.9398)
			(stroke
				(width 0.1524)
				(type default)
			)
			(layer "F.SilkS")
		)
		(fp_line
			(start -0.508 -0.9398)
			(end -0.508 0.9398)
			(stroke
				(width 0.1524)
				(type default)
			)
			(layer "F.SilkS")
		)
		(fp_rect
			(start -0.508 0.9398)
			(end 0.508 -0.9398)
			(stroke
				(width 0)
				(type default)
			)
			(fill no)
			(layer "F.CrtYd")
		)
		(fp_rect
			(start -0.508 0.9398)
			(end 0.508 -0.9398)
			(stroke
				(width 0)
				(type default)
			)
			(fill no)
			(layer "F.Fab")
		)
		(pad "1" smd custom
			(at 0 -0.4445 180)
			(size 0.1397 0.1397)
			(layers "F.Cu" "F.Mask" "F.Paste")
			(net "LED_DR_LED1")
			(options
				(clearance outline)
				(anchor circle)
			)
			(primitives
				(gr_poly
					(pts
						(arc
							(start -0.1778 -0.2794)
							(mid -0.249642 -0.249642)
							(end -0.2794 -0.1778)
						)
						(arc
							(start -0.2794 0.1778)
							(mid -0.249642 0.249642)
							(end -0.1778 0.2794)
						)
						(arc
							(start 0.1778 0.2794)
							(mid 0.249642 0.249642)
							(end 0.2794 0.1778)
						)
						(arc
							(start 0.2794 -0.1778)
							(mid 0.249642 -0.249642)
							(end 0.1778 -0.2794)
						)
					)
					(width 0)
					(fill yes)
				)
			)
		)
		(pad "2" smd custom
			(at 0 0.4445 180)
			(size 0.1397 0.1397)
			(layers "F.Cu" "F.Mask" "F.Paste")
			(net "BMC_ID_LED_R")
			(options
				(clearance outline)
				(anchor circle)
			)
			(primitives
				(gr_poly
					(pts
						(arc
							(start -0.1778 -0.2794)
							(mid -0.249642 -0.249642)
							(end -0.2794 -0.1778)
						)
						(arc
							(start -0.2794 0.1778)
							(mid -0.249642 0.249642)
							(end -0.1778 0.2794)
						)
						(arc
							(start 0.1778 0.2794)
							(mid 0.249642 0.249642)
							(end 0.2794 0.1778)
						)
						(arc
							(start 0.2794 -0.1778)
							(mid 0.249642 -0.249642)
							(end 0.1778 -0.2794)
						)
					)
					(width 0)
					(fill yes)
				)
			)
		)
	)
	(footprint ""
		(layer "F.Cu")
		(at 194.8688 -31.8262 90)
		(property "Reference" "R774"
			(at 0 0 90)
			(layer "F.SilkS")
			(hide yes)
			(effects
				(font
					(size 1.27 1.27)
				)
			)
		)
		(property "Value" "4K7R2F-GP"
			(at 0.064008 -3.993896 90)
			(unlocked yes)
			(layer "F.Fab")
			(hide yes)
			(effects
				(font
					(size 1.016 1.016)
					(thickness 0.1524)
				)
			)
		)
		(property "Device Type" "R402H16"
			(at 0.064008 -5.517896 90)
			(unlocked yes)
			(layer "F.Fab")
			(hide yes)
			(effects
				(font
					(size 1.016 1.016)
					(thickness 0.1524)
				)
			)
		)
		(duplicate_pad_numbers_are_jumpers no)
		(fp_line
			(start 0.508 -0.9398)
			(end -0.508 -0.9398)
			(stroke
				(width 0.1524)
				(type default)
			)
			(layer "F.SilkS")
		)
		(fp_line
			(start -0.508 -0.9398)
			(end -0.508 0.9398)
			(stroke
				(width 0.1524)
				(type default)
			)
			(layer "F.SilkS")
		)
		(fp_rect
			(start -0.508 0.9398)
			(end 0.508 -0.9398)
			(stroke
				(width 0)
				(type default)
			)
			(fill no)
			(layer "F.CrtYd")
		)
		(fp_rect
			(start -0.508 0.9398)
			(end 0.508 -0.9398)
			(stroke
				(width 0)
				(type default)
			)
			(fill no)
			(layer "F.Fab")
		)
		(pad "1" smd custom
			(at 0 -0.4445 90)
			(size 0.1397 0.1397)
			(layers "F.Cu" "F.Mask" "F.Paste")
			(net "GND")
			(options
				(clearance outline)
				(anchor circle)
			)
			(primitives
				(gr_poly
					(pts
						(arc
							(start -0.1778 -0.2794)
							(mid -0.249642 -0.249642)
							(end -0.2794 -0.1778)
						)
						(arc
							(start -0.2794 0.1778)
							(mid -0.249642 0.249642)
							(end -0.1778 0.2794)
						)
						(arc
							(start 0.1778 0.2794)
							(mid 0.249642 0.249642)
							(end 0.2794 0.1778)
						)
						(arc
							(start 0.2794 -0.1778)
							(mid 0.249642 -0.249642)
							(end 0.1778 -0.2794)
						)
					)
					(width 0)
					(fill yes)
				)
			)
		)
		(pad "2" smd custom
			(at 0 0.4445 90)
			(size 0.1397 0.1397)
			(layers "F.Cu" "F.Mask" "F.Paste")
			(net "U55_A2")
			(options
				(clearance outline)
				(anchor circle)
			)
			(primitives
				(gr_poly
					(pts
						(arc
							(start -0.1778 -0.2794)
							(mid -0.249642 -0.249642)
							(end -0.2794 -0.1778)
						)
						(arc
							(start -0.2794 0.1778)
							(mid -0.249642 0.249642)
							(end -0.1778 0.2794)
						)
						(arc
							(start 0.1778 0.2794)
							(mid 0.249642 0.249642)
							(end 0.2794 0.1778)
						)
						(arc
							(start 0.2794 -0.1778)
							(mid 0.249642 -0.249642)
							(end 0.1778 -0.2794)
						)
					)
					(width 0)
					(fill yes)
				)
			)
		)
	)
	(footprint ""
		(layer "F.Cu")
		(at 34.5186 -67.1322 -90)
		(property "Reference" "C332"
			(at 0 0 270)
			(layer "F.SilkS")
			(hide yes)
			(effects
				(font
					(size 1.27 1.27)
				)
			)
		)
		(property "Value" "SCD1U16V2JX-1-GP"
			(at 1.1811 -2.7051 270)
			(unlocked yes)
			(layer "F.Fab")
			(hide yes)
			(effects
				(font
					(size 1.016 1.016)
					(thickness 0.1524)
				)
			)
		)
		(property "Device Type" "C402H22"
			(at 1.1811 -4.2291 270)
			(unlocked yes)
			(layer "F.Fab")
			(hide yes)
			(effects
				(font
					(size 1.016 1.016)
					(thickness 0.1524)
				)
			)
		)
		(duplicate_pad_numbers_are_jumpers no)
		(fp_rect
			(start -0.4318 0.9525)
			(end 0.4318 -0.9525)
			(stroke
				(width 0)
				(type default)
			)
			(fill no)
			(layer "F.CrtYd")
		)
		(fp_rect
			(start -0.4318 0.9525)
			(end 0.4318 -0.9525)
			(stroke
				(width 0)
				(type default)
			)
			(fill no)
			(layer "F.Fab")
		)
		(pad "1" smd custom
			(at 0 -0.4445 270)
			(size 0.1524 0.1524)
			(layers "F.Cu" "F.Mask" "F.Paste")
			(net "P5V_USB_BP1_F")
			(options
				(clearance outline)
				(anchor circle)
			)
			(primitives
				(gr_poly
					(pts
						(arc
							(start 0.3048 -0.2032)
							(mid 0.275042 -0.275042)
							(end 0.2032 -0.3048)
						)
						(arc
							(start -0.2032 -0.3048)
							(mid -0.275042 -0.275042)
							(end -0.3048 -0.2032)
						)
						(arc
							(start -0.3048 0.2032)
							(mid -0.275042 0.275042)
							(end -0.2032 0.3048)
						)
						(arc
							(start 0.2032 0.3048)
							(mid 0.275042 0.275042)
							(end 0.3048 0.2032)
						)
					)
					(width 0)
					(fill yes)
				)
			)
		)
		(pad "2" smd custom
			(at 0 0.4445 270)
			(size 0.1524 0.1524)
			(layers "F.Cu" "F.Mask" "F.Paste")
			(net "GND")
			(options
				(clearance outline)
				(anchor circle)
			)
			(primitives
				(gr_poly
					(pts
						(arc
							(start 0.3048 -0.2032)
							(mid 0.275042 -0.275042)
							(end 0.2032 -0.3048)
						)
						(arc
							(start -0.2032 -0.3048)
							(mid -0.275042 -0.275042)
							(end -0.3048 -0.2032)
						)
						(arc
							(start -0.3048 0.2032)
							(mid -0.275042 0.275042)
							(end -0.2032 0.3048)
						)
						(arc
							(start 0.2032 0.3048)
							(mid 0.275042 0.275042)
							(end 0.3048 0.2032)
						)
					)
					(width 0)
					(fill yes)
				)
			)
		)
	)
	(footprint ""
		(layer "F.Cu")
		(at 80.6196 -136.7282 90)
		(property "Reference" "R3099"
			(at 0 0 90)
			(layer "F.SilkS")
			(hide yes)
			(effects
				(font
					(size 1.27 1.27)
				)
			)
		)
		(property "Value" "1KR2F-3-GP"
			(at 0.064008 -3.993896 90)
			(unlocked yes)
			(layer "F.Fab")
			(hide yes)
			(effects
				(font
					(size 1.016 1.016)
					(thickness 0.1524)
				)
			)
		)
		(property "Device Type" "R402H16"
			(at 0.064008 -5.517896 90)
			(unlocked yes)
			(layer "F.Fab")
			(hide yes)
			(effects
				(font
					(size 1.016 1.016)
					(thickness 0.1524)
				)
			)
		)
		(duplicate_pad_numbers_are_jumpers no)
		(fp_line
			(start 0.508 -0.9398)
			(end -0.508 -0.9398)
			(stroke
				(width 0.1524)
				(type default)
			)
			(layer "F.SilkS")
		)
		(fp_line
			(start -0.508 -0.9398)
			(end -0.508 0.9398)
			(stroke
				(width 0.1524)
				(type default)
			)
			(layer "F.SilkS")
		)
		(fp_rect
			(start -0.508 0.9398)
			(end 0.508 -0.9398)
			(stroke
				(width 0)
				(type default)
			)
			(fill no)
			(layer "F.CrtYd")
		)
		(fp_rect
			(start -0.508 0.9398)
			(end 0.508 -0.9398)
			(stroke
				(width 0)
				(type default)
			)
			(fill no)
			(layer "F.Fab")
		)
		(pad "1" smd custom
			(at 0 -0.4445 90)
			(size 0.1397 0.1397)
			(layers "F.Cu" "F.Mask" "F.Paste")
			(net "ADC_P1V26")
			(options
				(clearance outline)
				(anchor circle)
			)
			(primitives
				(gr_poly
					(pts
						(arc
							(start -0.1778 -0.2794)
							(mid -0.249642 -0.249642)
							(end -0.2794 -0.1778)
						)
						(arc
							(start -0.2794 0.1778)
							(mid -0.249642 0.249642)
							(end -0.1778 0.2794)
						)
						(arc
							(start 0.1778 0.2794)
							(mid 0.249642 0.249642)
							(end 0.2794 0.1778)
						)
						(arc
							(start 0.2794 -0.1778)
							(mid 0.249642 -0.249642)
							(end 0.1778 -0.2794)
						)
					)
					(width 0)
					(fill yes)
				)
			)
		)
		(pad "2" smd custom
			(at 0 0.4445 90)
			(size 0.1397 0.1397)
			(layers "F.Cu" "F.Mask" "F.Paste")
			(net "GND")
			(options
				(clearance outline)
				(anchor circle)
			)
			(primitives
				(gr_poly
					(pts
						(arc
							(start -0.1778 -0.2794)
							(mid -0.249642 -0.249642)
							(end -0.2794 -0.1778)
						)
						(arc
							(start -0.2794 0.1778)
							(mid -0.249642 0.249642)
							(end -0.1778 0.2794)
						)
						(arc
							(start 0.1778 0.2794)
							(mid 0.249642 0.249642)
							(end 0.2794 0.1778)
						)
						(arc
							(start 0.2794 -0.1778)
							(mid 0.249642 -0.249642)
							(end 0.1778 -0.2794)
						)
					)
					(width 0)
					(fill yes)
				)
			)
		)
	)
	(footprint ""
		(layer "F.Cu")
		(at 8.7376 -52.0446 -90)
		(property "Reference" "D11"
			(at 0 0 270)
			(layer "F.SilkS")
			(hide yes)
			(effects
				(font
					(size 1.27 1.27)
				)
			)
		)
		(property "Value" "PGB1010603MR-GP"
			(at -0.0254 -2.8956 270)
			(unlocked yes)
			(layer "F.Fab")
			(hide yes)
			(effects
				(font
					(size 1.016 1.016)
					(thickness 0.1524)
				)
			)
		)
		(property "Device Type" "L1608-UH15"
			(at -0.0254 -4.4196 270)
			(unlocked yes)
			(layer "F.Fab")
			(hide yes)
			(effects
				(font
					(size 1.016 1.016)
					(thickness 0.1524)
				)
			)
		)
		(duplicate_pad_numbers_are_jumpers no)
		(fp_line
			(start 0.254 0)
			(end -0.254 0)
			(stroke
				(width 0.2032)
				(type default)
			)
			(layer "F.SilkS")
		)
		(fp_rect
			(start -0.5842 1.3335)
			(end 0.5842 -1.3335)
			(stroke
				(width 0)
				(type default)
			)
			(fill no)
			(layer "F.CrtYd")
		)
		(fp_rect
			(start -0.5842 1.3335)
			(end 0.5842 -1.3335)
			(stroke
				(width 0)
				(type default)
			)
			(fill no)
			(layer "F.Fab")
		)
		(pad "1" smd custom
			(at 0 -0.762 270)
			(size 0.2159 0.2159)
			(layers "F.Cu" "F.Mask" "F.Paste")
			(net "NIC0_MDI0_P0_R")
			(options
				(clearance outline)
				(anchor circle)
			)
			(primitives
				(gr_poly
					(pts
						(arc
							(start -0.3302 -0.4318)
							(mid -0.402042 -0.402042)
							(end -0.4318 -0.3302)
						)
						(arc
							(start -0.4318 0.3302)
							(mid -0.402042 0.402042)
							(end -0.3302 0.4318)
						)
						(arc
							(start 0.3302 0.4318)
							(mid 0.402042 0.402042)
							(end 0.4318 0.3302)
						)
						(arc
							(start 0.4318 -0.3302)
							(mid 0.402042 -0.402042)
							(end 0.3302 -0.4318)
						)
					)
					(width 0)
					(fill yes)
				)
			)
		)
		(pad "2" smd custom
			(at 0 0.762 270)
			(size 0.2159 0.2159)
			(layers "F.Cu" "F.Mask" "F.Paste")
			(net "GND")
			(options
				(clearance outline)
				(anchor circle)
			)
			(primitives
				(gr_poly
					(pts
						(arc
							(start -0.3302 -0.4318)
							(mid -0.402042 -0.402042)
							(end -0.4318 -0.3302)
						)
						(arc
							(start -0.4318 0.3302)
							(mid -0.402042 0.402042)
							(end -0.3302 0.4318)
						)
						(arc
							(start 0.3302 0.4318)
							(mid 0.402042 0.402042)
							(end 0.4318 0.3302)
						)
						(arc
							(start 0.4318 -0.3302)
							(mid 0.402042 -0.402042)
							(end 0.3302 -0.4318)
						)
					)
					(width 0)
					(fill yes)
				)
			)
		)
	)
)
